(kicad_pcb
	(version 20260206)
	(generator "pcbnew")
	(generator_version "10.0")
	(general
		(thickness 1.6)
		(legacy_teardrops no)
	)
	(paper "A4")
	(title_block
		(title "panther-plus-userver — 13130-1b_20150205.brd")
		(comment 1 "Honey Badger (Wiwynn) / footprints 1312-1319 of 1509")
	)
	(layers
		(0 "F.Cu" signal "TOP")
		(4 "In1.Cu" signal "L2")
		(6 "In2.Cu" signal "L3")
		(8 "In3.Cu" signal "L4")
		(10 "In4.Cu" signal "L5")
		(12 "In5.Cu" signal "L6")
		(14 "In6.Cu" signal "L7")
		(16 "In7.Cu" signal "L8")
		(18 "In8.Cu" signal "L9")
		(20 "In9.Cu" signal "L10")
		(22 "In10.Cu" signal "L11")
		(2 "B.Cu" signal "BOTTOM")
		(9 "F.Adhes" user "F.Adhesive")
		(11 "B.Adhes" user "B.Adhesive")
		(13 "F.Paste" user "Package Geometry/Pastemask Top")
		(15 "B.Paste" user "Package Geometry/Pastemask Bottom")
		(5 "F.SilkS" user "Ref Des/Silkscreen Top")
		(7 "B.SilkS" user "Ref Des/Silkscreen Bottom")
		(1 "F.Mask" user "Board Geometry/Soldermask Top")
		(3 "B.Mask" user "Board Geometry/Soldermask Bottom")
		(17 "Dwgs.User" user "User.Drawings")
		(19 "Cmts.User" user "User.Comments")
		(21 "Eco1.User" user "User.Eco1")
		(23 "Eco2.User" user "User.Eco2")
		(25 "Edge.Cuts" user "Board Geometry/Outline")
		(27 "Margin" user)
		(31 "F.CrtYd" user "Package Geometry/Place Bound Top")
		(29 "B.CrtYd" user "Package Geometry/Place Bound Bottom")
		(35 "F.Fab" user "Ref Des/Assembly Top")
		(33 "B.Fab" user "Ref Des/Assembly Bottom")
	)
	(footprint ""
		(layer "B.Cu")
		(at 15.875 -55.372 -90)
		(property "Reference" "R370"
			(at 0 0 90)
			(layer "B.SilkS")
			(hide yes)
			(effects
				(font
					(size 1.27 1.27)
				)
				(justify mirror)
			)
		)
		(property "Value" "0R2J-2-GP"
			(at -1.7907 -1.1176 270)
			(unlocked yes)
			(layer "B.Fab")
			(hide yes)
			(effects
				(font
					(size 1.016 1.016)
					(thickness 0.1524)
				)
				(justify mirror)
			)
		)
		(property "Device Type" "R402H16"
			(at -1.7907 -2.6416 270)
			(unlocked yes)
			(layer "B.Fab")
			(hide yes)
			(effects
				(font
					(size 1.016 1.016)
					(thickness 0.1524)
				)
				(justify mirror)
			)
		)
		(duplicate_pad_numbers_are_jumpers no)
		(fp_rect
			(start 0.381 0.8382)
			(end -0.381 -0.8382)
			(stroke
				(width 0)
				(type default)
			)
			(fill no)
			(layer "B.CrtYd")
		)
		(fp_rect
			(start 0.381 0.8382)
			(end -0.381 -0.8382)
			(stroke
				(width 0)
				(type default)
			)
			(fill no)
			(layer "B.Fab")
		)
		(pad "1" smd custom
			(at 0 -0.4318 90)
			(size 0.127 0.127)
			(layers "B.Cu" "B.Mask" "B.Paste")
			(net "PMU_PLTRST#")
			(options
				(clearance outline)
				(anchor circle)
			)
			(primitives
				(gr_poly
					(pts
						(arc
							(start -0.2032 0.2794)
							(mid -0.239121 0.264521)
							(end -0.254 0.2286)
						)
						(arc
							(start -0.254 -0.2286)
							(mid -0.239121 -0.264521)
							(end -0.2032 -0.2794)
						)
						(arc
							(start 0.2032 -0.2794)
							(mid 0.239121 -0.264521)
							(end 0.254 -0.2286)
						)
						(arc
							(start 0.254 0.2286)
							(mid 0.239121 0.264521)
							(end 0.2032 0.2794)
						)
					)
					(width 0)
					(fill yes)
				)
			)
		)
		(pad "2" smd custom
			(at 0 0.4318 90)
			(size 0.127 0.127)
			(layers "B.Cu" "B.Mask" "B.Paste")
			(net "RST_PCIE_PCH_DEV_R#")
			(options
				(clearance outline)
				(anchor circle)
			)
			(primitives
				(gr_poly
					(pts
						(arc
							(start -0.2032 0.2794)
							(mid -0.239121 0.264521)
							(end -0.254 0.2286)
						)
						(arc
							(start -0.254 -0.2286)
							(mid -0.239121 -0.264521)
							(end -0.2032 -0.2794)
						)
						(arc
							(start 0.2032 -0.2794)
							(mid 0.239121 -0.264521)
							(end 0.254 -0.2286)
						)
						(arc
							(start 0.254 0.2286)
							(mid 0.239121 0.264521)
							(end 0.2032 0.2794)
						)
					)
					(width 0)
					(fill yes)
				)
			)
		)
	)
	(footprint ""
		(layer "B.Cu")
		(at 94.742 -18.5928 90)
		(property "Reference" "L7"
			(at 0 0 90)
			(layer "B.SilkS")
			(hide yes)
			(effects
				(font
					(size 1.27 1.27)
				)
				(justify mirror)
			)
		)
		(property "Value" "BLM18PG121SN1D-GP"
			(at 0.0254 -2.8956 90)
			(unlocked yes)
			(layer "B.Fab")
			(hide yes)
			(effects
				(font
					(size 1.016 1.016)
					(thickness 0.1524)
				)
				(justify mirror)
			)
		)
		(property "Device Type" "L1608-UH38"
			(at 0.0254 -4.4196 90)
			(unlocked yes)
			(layer "B.Fab")
			(hide yes)
			(effects
				(font
					(size 1.016 1.016)
					(thickness 0.1524)
				)
				(justify mirror)
			)
		)
		(duplicate_pad_numbers_are_jumpers no)
		(fp_line
			(start 0.4064 0)
			(end -0.4064 0)
			(stroke
				(width 0.2032)
				(type default)
			)
			(layer "B.SilkS")
		)
		(fp_rect
			(start 0.635 1.1811)
			(end -0.635 -1.1811)
			(stroke
				(width 0)
				(type default)
			)
			(fill no)
			(layer "B.CrtYd")
		)
		(fp_rect
			(start 0.635 1.1811)
			(end -0.635 -1.1811)
			(stroke
				(width 0)
				(type default)
			)
			(fill no)
			(layer "B.Fab")
		)
		(pad "1" smd custom
			(at 0 -0.6604 270)
			(size 0.19685 0.19685)
			(layers "B.Cu" "B.Mask" "B.Paste")
			(net "P1V0")
			(options
				(clearance outline)
				(anchor circle)
			)
			(primitives
				(gr_poly
					(pts
						(arc
							(start 0.508 0.2921)
							(mid 0.478242 0.363942)
							(end 0.4064 0.3937)
						)
						(arc
							(start -0.4064 0.3937)
							(mid -0.478242 0.363942)
							(end -0.508 0.2921)
						)
						(arc
							(start -0.508 -0.2921)
							(mid -0.478242 -0.363942)
							(end -0.4064 -0.3937)
						)
						(arc
							(start 0.4064 -0.3937)
							(mid 0.478242 -0.363942)
							(end 0.508 -0.2921)
						)
					)
					(width 0)
					(fill yes)
				)
			)
		)
		(pad "2" smd custom
			(at 0 0.6604 270)
			(size 0.19685 0.19685)
			(layers "B.Cu" "B.Mask" "B.Paste")
			(net "VCCA_PLLDDR1_AVN")
			(options
				(clearance outline)
				(anchor circle)
			)
			(primitives
				(gr_poly
					(pts
						(arc
							(start 0.508 0.2921)
							(mid 0.478242 0.363942)
							(end 0.4064 0.3937)
						)
						(arc
							(start -0.4064 0.3937)
							(mid -0.478242 0.363942)
							(end -0.508 0.2921)
						)
						(arc
							(start -0.508 -0.2921)
							(mid -0.478242 -0.363942)
							(end -0.4064 -0.3937)
						)
						(arc
							(start 0.4064 -0.3937)
							(mid 0.478242 -0.363942)
							(end 0.508 -0.2921)
						)
					)
					(width 0)
					(fill yes)
				)
			)
		)
	)
	(footprint ""
		(layer "B.Cu")
		(at 89.662 -39.243 180)
		(property "Reference" "R320"
			(at 0 0 0)
			(layer "B.SilkS")
			(hide yes)
			(effects
				(font
					(size 1.27 1.27)
				)
				(justify mirror)
			)
		)
		(property "Value" "49D9R2F-GP"
			(at -0.064008 -3.993896 180)
			(unlocked yes)
			(layer "B.Fab")
			(hide yes)
			(effects
				(font
					(size 1.016 1.016)
					(thickness 0.1524)
				)
				(justify mirror)
			)
		)
		(property "Device Type" "R402H16"
			(at -0.064008 -5.517896 180)
			(unlocked yes)
			(layer "B.Fab")
			(hide yes)
			(effects
				(font
					(size 1.016 1.016)
					(thickness 0.1524)
				)
				(justify mirror)
			)
		)
		(duplicate_pad_numbers_are_jumpers no)
		(fp_rect
			(start 0.381 0.8382)
			(end -0.381 -0.8382)
			(stroke
				(width 0)
				(type default)
			)
			(fill no)
			(layer "B.CrtYd")
		)
		(fp_rect
			(start 0.381 0.8382)
			(end -0.381 -0.8382)
			(stroke
				(width 0)
				(type default)
			)
			(fill no)
			(layer "B.Fab")
		)
		(pad "1" smd custom
			(at 0 -0.4318)
			(size 0.127 0.127)
			(layers "B.Cu" "B.Mask" "B.Paste")
			(net "RCOMP_CORE_LVT")
			(options
				(clearance outline)
				(anchor circle)
			)
			(primitives
				(gr_poly
					(pts
						(arc
							(start -0.2032 0.2794)
							(mid -0.239121 0.264521)
							(end -0.254 0.2286)
						)
						(arc
							(start -0.254 -0.2286)
							(mid -0.239121 -0.264521)
							(end -0.2032 -0.2794)
						)
						(arc
							(start 0.2032 -0.2794)
							(mid 0.239121 -0.264521)
							(end 0.254 -0.2286)
						)
						(arc
							(start 0.254 0.2286)
							(mid 0.239121 0.264521)
							(end 0.2032 0.2794)
						)
					)
					(width 0)
					(fill yes)
				)
			)
		)
		(pad "2" smd custom
			(at 0 0.4318)
			(size 0.127 0.127)
			(layers "B.Cu" "B.Mask" "B.Paste")
			(net "GND")
			(options
				(clearance outline)
				(anchor circle)
			)
			(primitives
				(gr_poly
					(pts
						(arc
							(start -0.2032 0.2794)
							(mid -0.239121 0.264521)
							(end -0.254 0.2286)
						)
						(arc
							(start -0.254 -0.2286)
							(mid -0.239121 -0.264521)
							(end -0.2032 -0.2794)
						)
						(arc
							(start 0.2032 -0.2794)
							(mid 0.239121 -0.264521)
							(end 0.254 -0.2286)
						)
						(arc
							(start 0.254 0.2286)
							(mid 0.239121 0.264521)
							(end 0.2032 0.2794)
						)
					)
					(width 0)
					(fill yes)
				)
			)
		)
	)
	(footprint ""
		(layer "B.Cu")
		(at 115.824 -41.3512 90)
		(property "Reference" "PTC5"
			(at 0 0 90)
			(layer "B.SilkS")
			(hide yes)
			(effects
				(font
					(size 1.27 1.27)
				)
				(justify mirror)
			)
		)
		(property "Value" "SE470UF2VDM-GP"
			(at 0 -9.6012 90)
			(unlocked yes)
			(layer "B.Fab")
			(hide yes)
			(effects
				(font
					(size 1.016 1.016)
					(thickness 0.1524)
				)
				(justify mirror)
			)
		)
		(property "Device Type" "CT7343H83"
			(at 0 -11.1252 90)
			(unlocked yes)
			(layer "B.Fab")
			(hide yes)
			(effects
				(font
					(size 1.016 1.016)
					(thickness 0.1524)
				)
				(justify mirror)
			)
		)
		(duplicate_pad_numbers_are_jumpers no)
		(fp_line
			(start 2.206752 -4.2926)
			(end -2.155698 -4.2926)
			(stroke
				(width 0.508)
				(type default)
			)
			(layer "B.SilkS")
		)
		(fp_rect
			(start 2.1463 3.6449)
			(end -2.1463 -3.6449)
			(stroke
				(width 0)
				(type default)
			)
			(fill no)
			(layer "B.CrtYd")
		)
		(fp_poly
			(pts
				(xy 3.81 3.9116) (xy 3.81 -3.9116) (xy 2.54 -3.9116) (xy 2.4003 -3.9116) (xy 2.4003 -4.0386) (xy -2.4003 -4.0386)
				(xy -2.4003 -3.9116) (xy -2.54 -3.9116) (xy -2.5654 -3.9116) (xy -3.81 -3.9116) (xy -3.81 -1.6256)
				(xy -2.1463 -1.6256) (xy -2.1463 -3.6449) (xy 2.1463 -3.6449) (xy 2.1463 3.6449) (xy -2.1463 3.6449)
				(xy -2.1463 -1.6129) (xy -3.81 -1.6129) (xy -3.81 3.9116) (xy -2.4003 3.9116) (xy -2.4003 3.9243)
				(xy -2.4003 4.0386) (xy 2.4003 4.0386) (xy 2.4003 3.9116)
			)
			(stroke
				(width 0)
				(type default)
			)
			(fill no)
			(layer "B.CrtYd")
		)
		(fp_rect
			(start 3.81 3.9116)
			(end 2.4003 -3.9116)
			(stroke
				(width 0)
				(type default)
			)
			(fill no)
			(layer "B.Fab")
		)
		(fp_rect
			(start -2.4003 3.9116)
			(end -3.81 -3.9116)
			(stroke
				(width 0)
				(type default)
			)
			(fill no)
			(layer "B.Fab")
		)
		(fp_rect
			(start 2.4003 4.0386)
			(end -2.4003 -4.0386)
			(stroke
				(width 0)
				(type default)
			)
			(fill no)
			(layer "B.Fab")
		)
		(pad "1" smd rect
			(at 0 -2.9591 270)
			(size 2.413 1.905)
			(layers "B.Cu" "B.Mask" "B.Paste")
			(net "PVCCP")
		)
		(pad "2" smd rect
			(at 0 2.9591 270)
			(size 2.413 1.905)
			(layers "B.Cu" "B.Mask" "B.Paste")
			(net "GND")
		)
	)
	(footprint ""
		(layer "B.Cu")
		(at 86.82736 -26.07056)
		(property "Reference" "R378"
			(at 0 0 0)
			(layer "B.SilkS")
			(hide yes)
			(effects
				(font
					(size 1.27 1.27)
				)
				(justify mirror)
			)
		)
		(property "Value" "1KR2F-3-GP"
			(at -0.064008 -3.993896 0)
			(unlocked yes)
			(layer "B.Fab")
			(hide yes)
			(effects
				(font
					(size 1.016 1.016)
					(thickness 0.1524)
				)
				(justify mirror)
			)
		)
		(property "Device Type" "R402H16"
			(at -0.064008 -5.517896 0)
			(unlocked yes)
			(layer "B.Fab")
			(hide yes)
			(effects
				(font
					(size 1.016 1.016)
					(thickness 0.1524)
				)
				(justify mirror)
			)
		)
		(duplicate_pad_numbers_are_jumpers no)
		(fp_rect
			(start 0.381 0.8382)
			(end -0.381 -0.8382)
			(stroke
				(width 0)
				(type default)
			)
			(fill no)
			(layer "B.CrtYd")
		)
		(fp_rect
			(start 0.381 0.8382)
			(end -0.381 -0.8382)
			(stroke
				(width 0)
				(type default)
			)
			(fill no)
			(layer "B.Fab")
		)
		(pad "1" smd custom
			(at 0 -0.4318 180)
			(size 0.127 0.127)
			(layers "B.Cu" "B.Mask" "B.Paste")
			(net "BD_REV_1")
			(options
				(clearance outline)
				(anchor circle)
			)
			(primitives
				(gr_poly
					(pts
						(arc
							(start -0.2032 0.2794)
							(mid -0.239121 0.264521)
							(end -0.254 0.2286)
						)
						(arc
							(start -0.254 -0.2286)
							(mid -0.239121 -0.264521)
							(end -0.2032 -0.2794)
						)
						(arc
							(start 0.2032 -0.2794)
							(mid 0.239121 -0.264521)
							(end 0.254 -0.2286)
						)
						(arc
							(start 0.254 0.2286)
							(mid 0.239121 0.264521)
							(end 0.2032 0.2794)
						)
					)
					(width 0)
					(fill yes)
				)
			)
		)
		(pad "2" smd custom
			(at 0 0.4318 180)
			(size 0.127 0.127)
			(layers "B.Cu" "B.Mask" "B.Paste")
			(net "GND")
			(options
				(clearance outline)
				(anchor circle)
			)
			(primitives
				(gr_poly
					(pts
						(arc
							(start -0.2032 0.2794)
							(mid -0.239121 0.264521)
							(end -0.254 0.2286)
						)
						(arc
							(start -0.254 -0.2286)
							(mid -0.239121 -0.264521)
							(end -0.2032 -0.2794)
						)
						(arc
							(start 0.2032 -0.2794)
							(mid 0.239121 -0.264521)
							(end 0.254 -0.2286)
						)
						(arc
							(start 0.254 0.2286)
							(mid 0.239121 0.264521)
							(end 0.2032 0.2794)
						)
					)
					(width 0)
					(fill yes)
				)
			)
		)
	)
	(footprint ""
		(layer "B.Cu")
		(at 54.229 -52.451 -90)
		(property "Reference" "PR155"
			(at 0 0 90)
			(layer "B.SilkS")
			(hide yes)
			(effects
				(font
					(size 1.27 1.27)
				)
				(justify mirror)
			)
		)
		(property "Value" "10KR2F-2-GP"
			(at -0.064008 -3.993896 270)
			(unlocked yes)
			(layer "B.Fab")
			(hide yes)
			(effects
				(font
					(size 1.016 1.016)
					(thickness 0.1524)
				)
				(justify mirror)
			)
		)
		(property "Device Type" "R402H16"
			(at -0.064008 -5.517896 270)
			(unlocked yes)
			(layer "B.Fab")
			(hide yes)
			(effects
				(font
					(size 1.016 1.016)
					(thickness 0.1524)
				)
				(justify mirror)
			)
		)
		(duplicate_pad_numbers_are_jumpers no)
		(fp_rect
			(start 0.381 0.8382)
			(end -0.381 -0.8382)
			(stroke
				(width 0)
				(type default)
			)
			(fill no)
			(layer "B.CrtYd")
		)
		(fp_rect
			(start 0.381 0.8382)
			(end -0.381 -0.8382)
			(stroke
				(width 0)
				(type default)
			)
			(fill no)
			(layer "B.Fab")
		)
		(pad "1" smd custom
			(at 0 -0.4318 90)
			(size 0.127 0.127)
			(layers "B.Cu" "B.Mask" "B.Paste")
			(net "P1V0_STBY_PG")
			(options
				(clearance outline)
				(anchor circle)
			)
			(primitives
				(gr_poly
					(pts
						(arc
							(start -0.2032 0.2794)
							(mid -0.239121 0.264521)
							(end -0.254 0.2286)
						)
						(arc
							(start -0.254 -0.2286)
							(mid -0.239121 -0.264521)
							(end -0.2032 -0.2794)
						)
						(arc
							(start 0.2032 -0.2794)
							(mid 0.239121 -0.264521)
							(end 0.254 -0.2286)
						)
						(arc
							(start 0.254 0.2286)
							(mid 0.239121 0.264521)
							(end 0.2032 0.2794)
						)
					)
					(width 0)
					(fill yes)
				)
			)
		)
		(pad "2" smd custom
			(at 0 0.4318 90)
			(size 0.127 0.127)
			(layers "B.Cu" "B.Mask" "B.Paste")
			(net "P3V3_STBY")
			(options
				(clearance outline)
				(anchor circle)
			)
			(primitives
				(gr_poly
					(pts
						(arc
							(start -0.2032 0.2794)
							(mid -0.239121 0.264521)
							(end -0.254 0.2286)
						)
						(arc
							(start -0.254 -0.2286)
							(mid -0.239121 -0.264521)
							(end -0.2032 -0.2794)
						)
						(arc
							(start 0.2032 -0.2794)
							(mid 0.239121 -0.264521)
							(end 0.254 -0.2286)
						)
						(arc
							(start 0.254 0.2286)
							(mid 0.239121 0.264521)
							(end 0.2032 0.2794)
						)
					)
					(width 0)
					(fill yes)
				)
			)
		)
	)
	(footprint ""
		(layer "B.Cu")
		(at 34.671 -17.018 90)
		(property "Reference" "R435"
			(at 0 0 90)
			(layer "B.SilkS")
			(hide yes)
			(effects
				(font
					(size 1.27 1.27)
				)
				(justify mirror)
			)
		)
		(property "Value" "0R2J-2-GP"
			(at -1.7907 -1.1176 90)
			(unlocked yes)
			(layer "B.Fab")
			(hide yes)
			(effects
				(font
					(size 1.016 1.016)
					(thickness 0.1524)
				)
				(justify mirror)
			)
		)
		(property "Device Type" "R402H16"
			(at -1.7907 -2.6416 90)
			(unlocked yes)
			(layer "B.Fab")
			(hide yes)
			(effects
				(font
					(size 1.016 1.016)
					(thickness 0.1524)
				)
				(justify mirror)
			)
		)
		(duplicate_pad_numbers_are_jumpers no)
		(fp_rect
			(start 0.381 0.8382)
			(end -0.381 -0.8382)
			(stroke
				(width 0)
				(type default)
			)
			(fill no)
			(layer "B.CrtYd")
		)
		(fp_rect
			(start 0.381 0.8382)
			(end -0.381 -0.8382)
			(stroke
				(width 0)
				(type default)
			)
			(fill no)
			(layer "B.Fab")
		)
		(pad "1" smd custom
			(at 0 -0.4318 270)
			(size 0.127 0.127)
			(layers "B.Cu" "B.Mask" "B.Paste")
			(net "SMBUS_HOST_CLK")
			(options
				(clearance outline)
				(anchor circle)
			)
			(primitives
				(gr_poly
					(pts
						(arc
							(start -0.2032 0.2794)
							(mid -0.239121 0.264521)
							(end -0.254 0.2286)
						)
						(arc
							(start -0.254 -0.2286)
							(mid -0.239121 -0.264521)
							(end -0.2032 -0.2794)
						)
						(arc
							(start 0.2032 -0.2794)
							(mid 0.239121 -0.264521)
							(end 0.254 -0.2286)
						)
						(arc
							(start 0.254 0.2286)
							(mid 0.239121 0.264521)
							(end 0.2032 0.2794)
						)
					)
					(width 0)
					(fill yes)
				)
			)
		)
		(pad "2" smd custom
			(at 0 0.4318 270)
			(size 0.127 0.127)
			(layers "B.Cu" "B.Mask" "B.Paste")
			(net "SMB_CLKBUFF_R_CLK")
			(options
				(clearance outline)
				(anchor circle)
			)
			(primitives
				(gr_poly
					(pts
						(arc
							(start -0.2032 0.2794)
							(mid -0.239121 0.264521)
							(end -0.254 0.2286)
						)
						(arc
							(start -0.254 -0.2286)
							(mid -0.239121 -0.264521)
							(end -0.2032 -0.2794)
						)
						(arc
							(start 0.2032 -0.2794)
							(mid 0.239121 -0.264521)
							(end 0.254 -0.2286)
						)
						(arc
							(start 0.254 0.2286)
							(mid 0.239121 0.264521)
							(end 0.2032 0.2794)
						)
					)
					(width 0)
					(fill yes)
				)
			)
		)
	)
	(footprint ""
		(layer "B.Cu")
		(at 72.898 -13.589)
		(property "Reference" "C279"
			(at 0 0 0)
			(layer "B.SilkS")
			(hide yes)
			(effects
				(font
					(size 1.27 1.27)
				)
				(justify mirror)
			)
		)
		(property "Value" "SCD1U16V2KX-3GP"
			(at -1.1811 -2.7051 0)
			(unlocked yes)
			(layer "B.Fab")
			(hide yes)
			(effects
				(font
					(size 1.016 1.016)
					(thickness 0.1524)
				)
				(justify mirror)
			)
		)
		(property "Device Type" "C402H22"
			(at -1.1811 -4.2291 0)
			(unlocked yes)
			(layer "B.Fab")
			(hide yes)
			(effects
				(font
					(size 1.016 1.016)
					(thickness 0.1524)
				)
				(justify mirror)
			)
		)
		(duplicate_pad_numbers_are_jumpers no)
		(fp_rect
			(start 0.381 0.7366)
			(end -0.381 -0.7366)
			(stroke
				(width 0)
				(type default)
			)
			(fill no)
			(layer "B.CrtYd")
		)
		(fp_rect
			(start 0.381 0.7366)
			(end -0.381 -0.7366)
			(stroke
				(width 0)
				(type default)
			)
			(fill no)
			(layer "B.Fab")
		)
		(pad "1" smd custom
			(at 0 -0.4572 180)
			(size 0.1143 0.1143)
			(layers "B.Cu" "B.Mask" "B.Paste")
			(net "P2E_CPU_SAS_C_TX_DN2")
			(options
				(clearance outline)
				(anchor circle)
			)
			(primitives
				(gr_poly
					(pts
						(arc
							(start -0.254 0.1778)
							(mid -0.239121 0.213721)
							(end -0.2032 0.2286)
						)
						(arc
							(start 0.2032 0.2286)
							(mid 0.239121 0.213721)
							(end 0.254 0.1778)
						)
						(arc
							(start 0.254 -0.1778)
							(mid 0.239121 -0.213721)
							(end 0.2032 -0.2286)
						)
						(arc
							(start -0.2032 -0.2286)
							(mid -0.239121 -0.213721)
							(end -0.254 -0.1778)
						)
					)
					(width 0)
					(fill yes)
				)
			)
		)
		(pad "2" smd custom
			(at 0 0.4572 180)
			(size 0.1143 0.1143)
			(layers "B.Cu" "B.Mask" "B.Paste")
			(net "P2E_CPU_SAS_TX_DN2")
			(options
				(clearance outline)
				(anchor circle)
			)
			(primitives
				(gr_poly
					(pts
						(arc
							(start -0.254 0.1778)
							(mid -0.239121 0.213721)
							(end -0.2032 0.2286)
						)
						(arc
							(start 0.2032 0.2286)
							(mid 0.239121 0.213721)
							(end 0.254 0.1778)
						)
						(arc
							(start 0.254 -0.1778)
							(mid 0.239121 -0.213721)
							(end 0.2032 -0.2286)
						)
						(arc
							(start -0.2032 -0.2286)
							(mid -0.239121 -0.213721)
							(end -0.254 -0.1778)
						)
					)
					(width 0)
					(fill yes)
				)
			)
		)
	)
)
